# BOM discovery v1 revB.xlsx — discovery (bom)
| Id | Reference | Footprint | Quantity | Designation | Manufacturer part number | Supplier part number | Manufacturer | Unit price | Total price |
| 1 | J1,J3 | Conn_02x04_4,2mm | 2 | Conn_02x04_CPU | 46207-0108 | 538-46207-0108 | Molex | 2.19 | 4.38 |
| 2 | J2,J4,J5,J6 | Conn_02x03_4,2mm | 4 | Conn_02x03_PCIe | 46207-0106 | 538-46207-0106 | Molex | 1.91 | 7.64 |
|  |  |  |  |  |  |  |  | Total: | 12.02 |
